(kicad_pcb
	(version 20260206)
	(generator "pcbnew")
	(generator_version "10.0")
	(general
		(thickness 1.6)
		(legacy_teardrops no)
	)
	(paper "A4")
	(title_block
		(title "15969-1a.1015WZS0858.brd")
		(comment 1 "Tioga Pass / footprints 188-194 of 295")
	)
	(layers
		(0 "F.Cu" signal "TOP")
		(4 "In1.Cu" signal "L2GND")
		(6 "In2.Cu" signal "L3")
		(8 "In3.Cu" signal "L4")
		(10 "In4.Cu" signal "L5GND")
		(2 "B.Cu" signal "BOTTOM")
		(9 "F.Adhes" user "F.Adhesive")
		(11 "B.Adhes" user "B.Adhesive")
		(13 "F.Paste" user "Package Geometry/Pastemask Top")
		(15 "B.Paste" user "Package Geometry/Pastemask Bottom")
		(5 "F.SilkS" user "Ref Des/Silkscreen Top")
		(7 "B.SilkS" user "Ref Des/Silkscreen Bottom")
		(1 "F.Mask" user "Board Geometry/Soldermask Top")
		(3 "B.Mask" user "Board Geometry/Soldermask Bottom")
		(17 "Dwgs.User" user "User.Drawings")
		(19 "Cmts.User" user "User.Comments")
		(21 "Eco1.User" user "User.Eco1")
		(23 "Eco2.User" user "User.Eco2")
		(25 "Edge.Cuts" user "Board Geometry/Outline")
		(27 "Margin" user)
		(31 "F.CrtYd" user "Package Geometry/Place Bound Top")
		(29 "B.CrtYd" user "Package Geometry/Place Bound Bottom")
		(35 "F.Fab" user "Ref Des/Assembly Top")
		(33 "B.Fab" user "Ref Des/Assembly Bottom")
	)
	(footprint ""
		(layer "B.Cu")
		(at 117.4496 -0.3302)
		(property "Reference" "R7"
			(at 0 0 0)
			(layer "B.SilkS")
			(hide yes)
			(effects
				(font
					(size 1.27 1.27)
				)
				(justify mirror)
			)
		)
		(property "Value" "4K7R2F-GP"
			(at -0.064008 -3.993896 0)
			(unlocked yes)
			(layer "B.Fab")
			(hide yes)
			(effects
				(font
					(size 1.016 1.016)
					(thickness 0.1524)
				)
				(justify mirror)
			)
		)
		(property "Device Type" "R402H16"
			(at -0.064008 -5.517896 0)
			(unlocked yes)
			(layer "B.Fab")
			(hide yes)
			(effects
				(font
					(size 1.016 1.016)
					(thickness 0.1524)
				)
				(justify mirror)
			)
		)
		(duplicate_pad_numbers_are_jumpers no)
		(fp_line
			(start -0.508 -0.9398)
			(end 0.508 -0.9398)
			(stroke
				(width 0.1524)
				(type default)
			)
			(layer "B.SilkS")
		)
		(fp_line
			(start 0.508 -0.9398)
			(end 0.508 0.9398)
			(stroke
				(width 0.1524)
				(type default)
			)
			(layer "B.SilkS")
		)
		(fp_rect
			(start 0.508 0.9398)
			(end -0.508 -0.9398)
			(stroke
				(width 0)
				(type default)
			)
			(fill no)
			(layer "B.CrtYd")
		)
		(fp_rect
			(start 0.508 0.9398)
			(end -0.508 -0.9398)
			(stroke
				(width 0)
				(type default)
			)
			(fill no)
			(layer "B.Fab")
		)
		(pad "1" smd custom
			(at 0 -0.4445 180)
			(size 0.1397 0.1397)
			(layers "B.Cu" "B.Mask" "B.Paste")
			(net "P3V3_STBY")
			(options
				(clearance outline)
				(anchor circle)
			)
			(primitives
				(gr_poly
					(pts
						(arc
							(start -0.1778 0.2794)
							(mid -0.249642 0.249642)
							(end -0.2794 0.1778)
						)
						(arc
							(start -0.2794 -0.1778)
							(mid -0.249642 -0.249642)
							(end -0.1778 -0.2794)
						)
						(arc
							(start 0.1778 -0.2794)
							(mid 0.249642 -0.249642)
							(end 0.2794 -0.1778)
						)
						(arc
							(start 0.2794 0.1778)
							(mid 0.249642 0.249642)
							(end 0.1778 0.2794)
						)
					)
					(width 0)
					(fill yes)
				)
			)
		)
		(pad "2" smd custom
			(at 0 0.4445 180)
			(size 0.1397 0.1397)
			(layers "B.Cu" "B.Mask" "B.Paste")
			(net "SMDAT_BMC_DEVICE")
			(options
				(clearance outline)
				(anchor circle)
			)
			(primitives
				(gr_poly
					(pts
						(arc
							(start -0.1778 0.2794)
							(mid -0.249642 0.249642)
							(end -0.2794 0.1778)
						)
						(arc
							(start -0.2794 -0.1778)
							(mid -0.249642 -0.249642)
							(end -0.1778 -0.2794)
						)
						(arc
							(start 0.1778 -0.2794)
							(mid 0.249642 -0.249642)
							(end 0.2794 -0.1778)
						)
						(arc
							(start 0.2794 0.1778)
							(mid 0.249642 0.249642)
							(end 0.1778 0.2794)
						)
					)
					(width 0)
					(fill yes)
				)
			)
		)
	)
	(footprint ""
		(layer "B.Cu")
		(at 122.9614 -25.0825)
		(property "Reference" "TP86"
			(at 0 0 0)
			(layer "B.SilkS")
			(hide yes)
			(effects
				(font
					(size 1.27 1.27)
				)
				(justify mirror)
			)
		)
		(property "Value" "TPAD24"
			(at 0 -1.6129 0)
			(unlocked yes)
			(layer "B.Fab")
			(hide yes)
			(effects
				(font
					(size 1.016 1.016)
					(thickness 0.1524)
				)
				(justify mirror)
			)
		)
		(property "Device Type" "TPAD24"
			(at 0 -3.1369 0)
			(unlocked yes)
			(layer "B.Fab")
			(hide yes)
			(effects
				(font
					(size 1.016 1.016)
					(thickness 0.1524)
				)
				(justify mirror)
			)
		)
		(duplicate_pad_numbers_are_jumpers no)
		(fp_poly
			(pts
				(arc
					(start 0.3048 0)
					(mid -0.3048 0)
					(end 0.3048 0)
				)
			)
			(stroke
				(width 0)
				(type default)
			)
			(fill no)
			(layer "B.CrtYd")
		)
		(fp_poly
			(pts
				(arc
					(start 0.6096 0)
					(mid -0.6096 0)
					(end 0.6096 0)
				)
			)
			(stroke
				(width 0)
				(type default)
			)
			(fill no)
			(layer "B.Fab")
		)
		(pad "1" smd circle
			(at 0 0 180)
			(size 0.6096 0.6096)
			(layers "B.Cu" "B.Mask" "B.Paste")
			(net "TP_USB_OCS_N4")
		)
	)
	(footprint ""
		(layer "B.Cu")
		(at 24.6253 -19.7993 90)
		(property "Reference" "R104"
			(at 0 0 90)
			(layer "B.SilkS")
			(hide yes)
			(effects
				(font
					(size 1.27 1.27)
				)
				(justify mirror)
			)
		)
		(property "Value" "0R2F-1-GP"
			(at -0.064008 -3.993896 90)
			(unlocked yes)
			(layer "B.Fab")
			(hide yes)
			(effects
				(font
					(size 1.016 1.016)
					(thickness 0.1524)
				)
				(justify mirror)
			)
		)
		(property "Device Type" "R402H16"
			(at -0.064008 -5.517896 90)
			(unlocked yes)
			(layer "B.Fab")
			(hide yes)
			(effects
				(font
					(size 1.016 1.016)
					(thickness 0.1524)
				)
				(justify mirror)
			)
		)
		(duplicate_pad_numbers_are_jumpers no)
		(fp_line
			(start 0.508 -0.9398)
			(end 0.508 0.9398)
			(stroke
				(width 0.1524)
				(type default)
			)
			(layer "B.SilkS")
		)
		(fp_line
			(start -0.508 -0.9398)
			(end 0.508 -0.9398)
			(stroke
				(width 0.1524)
				(type default)
			)
			(layer "B.SilkS")
		)
		(fp_rect
			(start 0.508 0.9398)
			(end -0.508 -0.9398)
			(stroke
				(width 0)
				(type default)
			)
			(fill no)
			(layer "B.CrtYd")
		)
		(fp_rect
			(start 0.508 0.9398)
			(end -0.508 -0.9398)
			(stroke
				(width 0)
				(type default)
			)
			(fill no)
			(layer "B.Fab")
		)
		(pad "1" smd custom
			(at 0 -0.4445 270)
			(size 0.1397 0.1397)
			(layers "B.Cu" "B.Mask" "B.Paste")
			(net "SMB_VMONITOR_ATX_MUX_SDA")
			(options
				(clearance outline)
				(anchor circle)
			)
			(primitives
				(gr_poly
					(pts
						(arc
							(start -0.1778 0.2794)
							(mid -0.249642 0.249642)
							(end -0.2794 0.1778)
						)
						(arc
							(start -0.2794 -0.1778)
							(mid -0.249642 -0.249642)
							(end -0.1778 -0.2794)
						)
						(arc
							(start 0.1778 -0.2794)
							(mid 0.249642 -0.249642)
							(end 0.2794 -0.1778)
						)
						(arc
							(start 0.2794 0.1778)
							(mid 0.249642 0.249642)
							(end 0.1778 0.2794)
						)
					)
					(width 0)
					(fill yes)
				)
			)
		)
		(pad "2" smd custom
			(at 0 0.4445 270)
			(size 0.1397 0.1397)
			(layers "B.Cu" "B.Mask" "B.Paste")
			(net "SMDAT_BMC_DEVICE")
			(options
				(clearance outline)
				(anchor circle)
			)
			(primitives
				(gr_poly
					(pts
						(arc
							(start -0.1778 0.2794)
							(mid -0.249642 0.249642)
							(end -0.2794 0.1778)
						)
						(arc
							(start -0.2794 -0.1778)
							(mid -0.249642 -0.249642)
							(end -0.1778 -0.2794)
						)
						(arc
							(start 0.1778 -0.2794)
							(mid 0.249642 -0.249642)
							(end 0.2794 -0.1778)
						)
						(arc
							(start 0.2794 0.1778)
							(mid 0.249642 0.249642)
							(end 0.1778 0.2794)
						)
					)
					(width 0)
					(fill yes)
				)
			)
		)
	)
	(footprint ""
		(layer "B.Cu")
		(at 18.3261 -11.0236)
		(property "Reference" "PR5"
			(at 0 0 0)
			(layer "B.SilkS")
			(hide yes)
			(effects
				(font
					(size 1.27 1.27)
				)
				(justify mirror)
			)
		)
		(property "Value" "2K2R2F-GP"
			(at -0.064008 -3.993896 0)
			(unlocked yes)
			(layer "B.Fab")
			(hide yes)
			(effects
				(font
					(size 1.016 1.016)
					(thickness 0.1524)
				)
				(justify mirror)
			)
		)
		(property "Device Type" "R402H16"
			(at -0.064008 -5.517896 0)
			(unlocked yes)
			(layer "B.Fab")
			(hide yes)
			(effects
				(font
					(size 1.016 1.016)
					(thickness 0.1524)
				)
				(justify mirror)
			)
		)
		(duplicate_pad_numbers_are_jumpers no)
		(fp_line
			(start -0.508 -0.9398)
			(end 0.508 -0.9398)
			(stroke
				(width 0.1524)
				(type default)
			)
			(layer "B.SilkS")
		)
		(fp_line
			(start 0.508 -0.9398)
			(end 0.508 0.9398)
			(stroke
				(width 0.1524)
				(type default)
			)
			(layer "B.SilkS")
		)
		(fp_rect
			(start 0.508 0.9398)
			(end -0.508 -0.9398)
			(stroke
				(width 0)
				(type default)
			)
			(fill no)
			(layer "B.CrtYd")
		)
		(fp_rect
			(start 0.508 0.9398)
			(end -0.508 -0.9398)
			(stroke
				(width 0)
				(type default)
			)
			(fill no)
			(layer "B.Fab")
		)
		(pad "1" smd custom
			(at 0 -0.4445 180)
			(size 0.1397 0.1397)
			(layers "B.Cu" "B.Mask" "B.Paste")
			(net "P3V3_FB")
			(options
				(clearance outline)
				(anchor circle)
			)
			(primitives
				(gr_poly
					(pts
						(arc
							(start -0.1778 0.2794)
							(mid -0.249642 0.249642)
							(end -0.2794 0.1778)
						)
						(arc
							(start -0.2794 -0.1778)
							(mid -0.249642 -0.249642)
							(end -0.1778 -0.2794)
						)
						(arc
							(start 0.1778 -0.2794)
							(mid 0.249642 -0.249642)
							(end 0.2794 -0.1778)
						)
						(arc
							(start 0.2794 0.1778)
							(mid 0.249642 0.249642)
							(end 0.1778 0.2794)
						)
					)
					(width 0)
					(fill yes)
				)
			)
		)
		(pad "2" smd custom
			(at 0 0.4445 180)
			(size 0.1397 0.1397)
			(layers "B.Cu" "B.Mask" "B.Paste")
			(net "GND")
			(options
				(clearance outline)
				(anchor circle)
			)
			(primitives
				(gr_poly
					(pts
						(arc
							(start -0.1778 0.2794)
							(mid -0.249642 0.249642)
							(end -0.2794 0.1778)
						)
						(arc
							(start -0.2794 -0.1778)
							(mid -0.249642 -0.249642)
							(end -0.1778 -0.2794)
						)
						(arc
							(start 0.1778 -0.2794)
							(mid 0.249642 -0.249642)
							(end 0.2794 -0.1778)
						)
						(arc
							(start 0.2794 0.1778)
							(mid 0.249642 0.249642)
							(end 0.1778 0.2794)
						)
					)
					(width 0)
					(fill yes)
				)
			)
		)
	)
	(footprint ""
		(layer "B.Cu")
		(at 124.3838 -0.1016)
		(property "Reference" "R18"
			(at 0 0 0)
			(layer "B.SilkS")
			(hide yes)
			(effects
				(font
					(size 1.27 1.27)
				)
				(justify mirror)
			)
		)
		(property "Value" "10KR2F-2-GP"
			(at -0.064008 -3.993896 0)
			(unlocked yes)
			(layer "B.Fab")
			(hide yes)
			(effects
				(font
					(size 1.016 1.016)
					(thickness 0.1524)
				)
				(justify mirror)
			)
		)
		(property "Device Type" "R402H16"
			(at -0.064008 -5.517896 0)
			(unlocked yes)
			(layer "B.Fab")
			(hide yes)
			(effects
				(font
					(size 1.016 1.016)
					(thickness 0.1524)
				)
				(justify mirror)
			)
		)
		(duplicate_pad_numbers_are_jumpers no)
		(fp_line
			(start -0.508 -0.9398)
			(end 0.508 -0.9398)
			(stroke
				(width 0.1524)
				(type default)
			)
			(layer "B.SilkS")
		)
		(fp_line
			(start 0.508 -0.9398)
			(end 0.508 0.9398)
			(stroke
				(width 0.1524)
				(type default)
			)
			(layer "B.SilkS")
		)
		(fp_rect
			(start 0.508 0.9398)
			(end -0.508 -0.9398)
			(stroke
				(width 0)
				(type default)
			)
			(fill no)
			(layer "B.CrtYd")
		)
		(fp_rect
			(start 0.508 0.9398)
			(end -0.508 -0.9398)
			(stroke
				(width 0)
				(type default)
			)
			(fill no)
			(layer "B.Fab")
		)
		(pad "1" smd custom
			(at 0 -0.4445 180)
			(size 0.1397 0.1397)
			(layers "B.Cu" "B.Mask" "B.Paste")
			(net "SMB_PCH_ALERT_N")
			(options
				(clearance outline)
				(anchor circle)
			)
			(primitives
				(gr_poly
					(pts
						(arc
							(start -0.1778 0.2794)
							(mid -0.249642 0.249642)
							(end -0.2794 0.1778)
						)
						(arc
							(start -0.2794 -0.1778)
							(mid -0.249642 -0.249642)
							(end -0.1778 -0.2794)
						)
						(arc
							(start 0.1778 -0.2794)
							(mid 0.249642 -0.249642)
							(end 0.2794 -0.1778)
						)
						(arc
							(start 0.2794 0.1778)
							(mid 0.249642 0.249642)
							(end 0.1778 0.2794)
						)
					)
					(width 0)
					(fill yes)
				)
			)
		)
		(pad "2" smd custom
			(at 0 0.4445 180)
			(size 0.1397 0.1397)
			(layers "B.Cu" "B.Mask" "B.Paste")
			(net "P3V3_STBY")
			(options
				(clearance outline)
				(anchor circle)
			)
			(primitives
				(gr_poly
					(pts
						(arc
							(start -0.1778 0.2794)
							(mid -0.249642 0.249642)
							(end -0.2794 0.1778)
						)
						(arc
							(start -0.2794 -0.1778)
							(mid -0.249642 -0.249642)
							(end -0.1778 -0.2794)
						)
						(arc
							(start 0.1778 -0.2794)
							(mid 0.249642 -0.249642)
							(end 0.2794 -0.1778)
						)
						(arc
							(start 0.2794 0.1778)
							(mid 0.249642 0.249642)
							(end 0.1778 0.2794)
						)
					)
					(width 0)
					(fill yes)
				)
			)
		)
	)
	(footprint ""
		(layer "B.Cu")
		(at 16.2306 -8.5217 -90)
		(property "Reference" "PR6"
			(at 0 0 90)
			(layer "B.SilkS")
			(hide yes)
			(effects
				(font
					(size 1.27 1.27)
				)
				(justify mirror)
			)
		)
		(property "Value" "30K1R2F-L-GP"
			(at -0.064008 -3.993896 270)
			(unlocked yes)
			(layer "B.Fab")
			(hide yes)
			(effects
				(font
					(size 1.016 1.016)
					(thickness 0.1524)
				)
				(justify mirror)
			)
		)
		(property "Device Type" "R402H16"
			(at -0.064008 -5.517896 270)
			(unlocked yes)
			(layer "B.Fab")
			(hide yes)
			(effects
				(font
					(size 1.016 1.016)
					(thickness 0.1524)
				)
				(justify mirror)
			)
		)
		(duplicate_pad_numbers_are_jumpers no)
		(fp_line
			(start -0.508 -0.9398)
			(end 0.508 -0.9398)
			(stroke
				(width 0.1524)
				(type default)
			)
			(layer "B.SilkS")
		)
		(fp_line
			(start 0.508 -0.9398)
			(end 0.508 0.9398)
			(stroke
				(width 0.1524)
				(type default)
			)
			(layer "B.SilkS")
		)
		(fp_rect
			(start 0.508 0.9398)
			(end -0.508 -0.9398)
			(stroke
				(width 0)
				(type default)
			)
			(fill no)
			(layer "B.CrtYd")
		)
		(fp_rect
			(start 0.508 0.9398)
			(end -0.508 -0.9398)
			(stroke
				(width 0)
				(type default)
			)
			(fill no)
			(layer "B.Fab")
		)
		(pad "1" smd custom
			(at 0 -0.4445 90)
			(size 0.1397 0.1397)
			(layers "B.Cu" "B.Mask" "B.Paste")
			(net "P3V3_MODE")
			(options
				(clearance outline)
				(anchor circle)
			)
			(primitives
				(gr_poly
					(pts
						(arc
							(start -0.1778 0.2794)
							(mid -0.249642 0.249642)
							(end -0.2794 0.1778)
						)
						(arc
							(start -0.2794 -0.1778)
							(mid -0.249642 -0.249642)
							(end -0.1778 -0.2794)
						)
						(arc
							(start 0.1778 -0.2794)
							(mid 0.249642 -0.249642)
							(end 0.2794 -0.1778)
						)
						(arc
							(start 0.2794 0.1778)
							(mid 0.249642 0.249642)
							(end 0.1778 0.2794)
						)
					)
					(width 0)
					(fill yes)
				)
			)
		)
		(pad "2" smd custom
			(at 0 0.4445 90)
			(size 0.1397 0.1397)
			(layers "B.Cu" "B.Mask" "B.Paste")
			(net "AGND_P3V3")
			(options
				(clearance outline)
				(anchor circle)
			)
			(primitives
				(gr_poly
					(pts
						(arc
							(start -0.1778 0.2794)
							(mid -0.249642 0.249642)
							(end -0.2794 0.1778)
						)
						(arc
							(start -0.2794 -0.1778)
							(mid -0.249642 -0.249642)
							(end -0.1778 -0.2794)
						)
						(arc
							(start 0.1778 -0.2794)
							(mid 0.249642 -0.249642)
							(end 0.2794 -0.1778)
						)
						(arc
							(start 0.2794 0.1778)
							(mid 0.249642 0.249642)
							(end 0.1778 0.2794)
						)
					)
					(width 0)
					(fill yes)
				)
			)
		)
	)
	(footprint ""
		(layer "B.Cu")
		(at 129.7686 -29.464 90)
		(property "Reference" "C61"
			(at 0 0 90)
			(layer "B.SilkS")
			(hide yes)
			(effects
				(font
					(size 1.27 1.27)
				)
				(justify mirror)
			)
		)
		(property "Value" "SC2D2U10V3KX-2GP-U1"
			(at 0 -2.8194 90)
			(unlocked yes)
			(layer "B.Fab")
			(hide yes)
			(effects
				(font
					(size 1.016 1.016)
					(thickness 0.1524)
				)
				(justify mirror)
			)
		)
		(property "Device Type" "C603H40"
			(at 0 -4.3434 90)
			(unlocked yes)
			(layer "B.Fab")
			(hide yes)
			(effects
				(font
					(size 1.016 1.016)
					(thickness 0.1524)
				)
				(justify mirror)
			)
		)
		(duplicate_pad_numbers_are_jumpers no)
		(fp_line
			(start -0.508 0)
			(end 0.508 0)
			(stroke
				(width 0.2032)
				(type default)
			)
			(layer "B.SilkS")
		)
		(fp_rect
			(start 0.5842 1.3335)
			(end -0.5842 -1.3335)
			(stroke
				(width 0)
				(type default)
			)
			(fill no)
			(layer "B.CrtYd")
		)
		(fp_rect
			(start 0.5842 1.3335)
			(end -0.5842 -1.3335)
			(stroke
				(width 0)
				(type default)
			)
			(fill no)
			(layer "B.Fab")
		)
		(pad "1" smd custom
			(at 0 -0.762 270)
			(size 0.2159 0.2159)
			(layers "B.Cu" "B.Mask" "B.Paste")
			(net "P3V3_USB_HUB")
			(options
				(clearance outline)
				(anchor circle)
			)
			(primitives
				(gr_poly
					(pts
						(arc
							(start -0.3302 0.4318)
							(mid -0.402042 0.402042)
							(end -0.4318 0.3302)
						)
						(arc
							(start -0.4318 -0.3302)
							(mid -0.402042 -0.402042)
							(end -0.3302 -0.4318)
						)
						(arc
							(start 0.3302 -0.4318)
							(mid 0.402042 -0.402042)
							(end 0.4318 -0.3302)
						)
						(arc
							(start 0.4318 0.3302)
							(mid 0.402042 0.402042)
							(end 0.3302 0.4318)
						)
					)
					(width 0)
					(fill yes)
				)
			)
		)
		(pad "2" smd custom
			(at 0 0.762 270)
			(size 0.2159 0.2159)
			(layers "B.Cu" "B.Mask" "B.Paste")
			(net "GND")
			(options
				(clearance outline)
				(anchor circle)
			)
			(primitives
				(gr_poly
					(pts
						(arc
							(start -0.3302 0.4318)
							(mid -0.402042 0.402042)
							(end -0.4318 0.3302)
						)
						(arc
							(start -0.4318 -0.3302)
							(mid -0.402042 -0.402042)
							(end -0.3302 -0.4318)
						)
						(arc
							(start 0.3302 -0.4318)
							(mid 0.402042 -0.402042)
							(end 0.4318 -0.3302)
						)
						(arc
							(start 0.4318 0.3302)
							(mid 0.402042 0.402042)
							(end 0.3302 0.4318)
						)
					)
					(width 0)
					(fill yes)
				)
			)
		)
	)
)
